(kicad_pcb
	(version 20241229)
	(generator "pcbnew")
	(generator_version "9.0")
	(general
		(thickness 1.599998)
		(legacy_teardrops no)
	)
	(paper "A4")
	(title_block
		(date "2023-02-12")
		(rev "1.1.5")
		(comment 9 "footprints 147-151 of 473")
	)
	(layers
		(0 "F.Cu" signal)
		(4 "In1.Cu" power "In1.GND")
		(6 "In2.Cu" signal)
		(8 "In3.Cu" power "In3.GND")
		(10 "In4.Cu" power "In4.VCC")
		(12 "In5.Cu" signal)
		(14 "In6.Cu" power "In6.VCC")
		(2 "B.Cu" signal)
		(9 "F.Adhes" user "F.Adhesive")
		(11 "B.Adhes" user "B.Adhesive")
		(13 "F.Paste" user)
		(15 "B.Paste" user)
		(5 "F.SilkS" user "F.Silkscreen")
		(7 "B.SilkS" user "B.Silkscreen")
		(1 "F.Mask" user)
		(3 "B.Mask" user)
		(17 "Dwgs.User" user "User.Drawings")
		(19 "Cmts.User" user "User.Comments")
		(21 "Eco1.User" user "User.Eco1")
		(23 "Eco2.User" user "User.Eco2")
		(25 "Edge.Cuts" user)
		(27 "Margin" user)
		(31 "F.CrtYd" user "F.Courtyard")
		(29 "B.CrtYd" user "B.Courtyard")
		(35 "F.Fab" user)
		(33 "B.Fab" user)
	)
	(footprint "antmicro-footprints:SC70-3"
		(layer "F.Cu")
		(at 194.736328 74.697157 90)
		(property "Reference" "Q3"
			(at -0.602843 -1.336328 90)
			(layer "F.SilkS")
			(effects
				(font
					(size 0.7 0.7)
					(thickness 0.15)
				)
				(justify left bottom)
			)
		)
		(property "Value" "BSS138PW"
			(at 0 2.3 90)
			(layer "F.Fab")
			(effects
				(font
					(size 0.7 0.7)
					(thickness 0.15)
				)
				(justify left bottom)
			)
		)
		(property "Description" "60 V, 320 mA N-channel enhancement mode Trench MOSFET, SC-70-3 aka SOT-323 package"
			(at 0 0 90)
			(layer "F.Fab")
			(hide yes)
			(effects
				(font
					(size 1.27 1.27)
					(thickness 0.15)
				)
			)
		)
		(property "Author" "Antmicro"
			(at 269.433485 -120.039171 0)
			(layer "F.Fab")
			(hide yes)
			(effects
				(font
					(size 1 1)
					(thickness 0.15)
				)
			)
		)
		(property "License" "Apache-2.0"
			(at 269.433485 -120.039171 0)
			(layer "F.Fab")
			(hide yes)
			(effects
				(font
					(size 1 1)
					(thickness 0.15)
				)
			)
		)
		(property "MPN" "BSS138PW"
			(at 269.433485 -120.039171 0)
			(layer "F.Fab")
			(hide yes)
			(effects
				(font
					(size 1 1)
					(thickness 0.15)
				)
			)
		)
		(property "Manufacturer" "Nexperia"
			(at 269.433485 -120.039171 0)
			(layer "F.Fab")
			(hide yes)
			(effects
				(font
					(size 1 1)
					(thickness 0.15)
				)
			)
		)
		(sheetname "Interfaces")
		(sheetfile "interfaces.kicad_sch")
		(attr smd)
		(fp_line
			(start -0.3 -1)
			(end 0.627 -0.999)
			(stroke
				(width 0.15)
				(type solid)
			)
			(layer "F.SilkS")
		)
		(fp_line
			(start 0.627 -0.6)
			(end 0.627 -0.999)
			(stroke
				(width 0.15)
				(type solid)
			)
			(layer "F.SilkS")
		)
		(fp_line
			(start 0.627 0.6)
			(end 0.627 1.001)
			(stroke
				(width 0.15)
				(type solid)
			)
			(layer "F.SilkS")
		)
		(fp_line
			(start -0.3 1)
			(end 0.627 1.001)
			(stroke
				(width 0.15)
				(type solid)
			)
			(layer "F.SilkS")
		)
		(fp_line
			(start 0.9 -1.3)
			(end 0.9 -0.4)
			(stroke
				(width 0.05)
				(type solid)
			)
			(layer "F.CrtYd")
		)
		(fp_line
			(start -0.9 -1.3)
			(end 0.9 -1.3)
			(stroke
				(width 0.05)
				(type solid)
			)
			(layer "F.CrtYd")
		)
		(fp_line
			(start -0.9 -1.3)
			(end -0.9 -1)
			(stroke
				(width 0.05)
				(type solid)
			)
			(layer "F.CrtYd")
		)
		(fp_line
			(start -0.9 -1)
			(end -1.4 -1)
			(stroke
				(width 0.05)
				(type solid)
			)
			(layer "F.CrtYd")
		)
		(fp_line
			(start 1.4 -0.4)
			(end 1.4 0.4)
			(stroke
				(width 0.05)
				(type solid)
			)
			(layer "F.CrtYd")
		)
		(fp_line
			(start 0.9 -0.4)
			(end 1.4 -0.4)
			(stroke
				(width 0.05)
				(type solid)
			)
			(layer "F.CrtYd")
		)
		(fp_line
			(start 1.4 0.4)
			(end 0.9 0.4)
			(stroke
				(width 0.05)
				(type solid)
			)
			(layer "F.CrtYd")
		)
		(fp_line
			(start 0.9 0.4)
			(end 0.9 1.3)
			(stroke
				(width 0.05)
				(type solid)
			)
			(layer "F.CrtYd")
		)
		(fp_line
			(start -0.9 1)
			(end -1.4 1)
			(stroke
				(width 0.05)
				(type solid)
			)
			(layer "F.CrtYd")
		)
		(fp_line
			(start -1.4 1)
			(end -1.4 -1)
			(stroke
				(width 0.05)
				(type solid)
			)
			(layer "F.CrtYd")
		)
		(fp_line
			(start 0.9 1.3)
			(end -0.9 1.3)
			(stroke
				(width 0.05)
				(type solid)
			)
			(layer "F.CrtYd")
		)
		(fp_line
			(start -0.9 1.3)
			(end -0.9 1)
			(stroke
				(width 0.05)
				(type solid)
			)
			(layer "F.CrtYd")
		)
		(fp_rect
			(start -0.623 -0.999)
			(end 0.627 1.001)
			(stroke
				(width 0.15)
				(type solid)
			)
			(fill no)
			(layer "F.Fab")
		)
		(pad "1" smd rect
			(at -0.95 -0.65 180)
			(size 0.6 0.8)
			(layers "F.Cu" "F.Mask" "F.Paste")
			(net 59 "USR_LED2")
			(pinfunction "G")
			(pintype "bidirectional")
		)
		(pad "2" smd rect
			(at -0.95 0.65 180)
			(size 0.6 0.8)
			(layers "F.Cu" "F.Mask" "F.Paste")
			(net 5 "GND")
			(pinfunction "S")
			(pintype "bidirectional")
		)
		(pad "3" smd rect
			(at 0.95 0 180)
			(size 0.6 0.8)
			(layers "F.Cu" "F.Mask" "F.Paste")
			(net 228 "Net-(Q3-D)")
			(pinfunction "D")
			(pintype "bidirectional")
		)
	)
	(footprint "antmicro-footprints:SC70-3"
		(layer "F.Cu")
		(at 202.736328 74.697157 90)
		(property "Reference" "Q4"
			(at -0.602843 -1.336328 90)
			(layer "F.SilkS")
			(effects
				(font
					(size 0.7 0.7)
					(thickness 0.15)
				)
				(justify left bottom)
			)
		)
		(property "Value" "BSS138PW"
			(at 0 2.3 90)
			(layer "F.Fab")
			(effects
				(font
					(size 0.7 0.7)
					(thickness 0.15)
				)
				(justify left bottom)
			)
		)
		(property "Description" "60 V, 320 mA N-channel enhancement mode Trench MOSFET, SC-70-3 aka SOT-323 package"
			(at 0 0 90)
			(layer "F.Fab")
			(hide yes)
			(effects
				(font
					(size 1.27 1.27)
					(thickness 0.15)
				)
			)
		)
		(property "Author" "Antmicro"
			(at 277.433485 -128.039171 0)
			(layer "F.Fab")
			(hide yes)
			(effects
				(font
					(size 1 1)
					(thickness 0.15)
				)
			)
		)
		(property "License" "Apache-2.0"
			(at 277.433485 -128.039171 0)
			(layer "F.Fab")
			(hide yes)
			(effects
				(font
					(size 1 1)
					(thickness 0.15)
				)
			)
		)
		(property "MPN" "BSS138PW"
			(at 277.433485 -128.039171 0)
			(layer "F.Fab")
			(hide yes)
			(effects
				(font
					(size 1 1)
					(thickness 0.15)
				)
			)
		)
		(property "Manufacturer" "Nexperia"
			(at 277.433485 -128.039171 0)
			(layer "F.Fab")
			(hide yes)
			(effects
				(font
					(size 1 1)
					(thickness 0.15)
				)
			)
		)
		(sheetname "Interfaces")
		(sheetfile "interfaces.kicad_sch")
		(attr smd)
		(fp_line
			(start -0.3 -1)
			(end 0.627 -0.999)
			(stroke
				(width 0.15)
				(type solid)
			)
			(layer "F.SilkS")
		)
		(fp_line
			(start 0.627 -0.6)
			(end 0.627 -0.999)
			(stroke
				(width 0.15)
				(type solid)
			)
			(layer "F.SilkS")
		)
		(fp_line
			(start 0.627 0.6)
			(end 0.627 1.001)
			(stroke
				(width 0.15)
				(type solid)
			)
			(layer "F.SilkS")
		)
		(fp_line
			(start -0.3 1)
			(end 0.627 1.001)
			(stroke
				(width 0.15)
				(type solid)
			)
			(layer "F.SilkS")
		)
		(fp_line
			(start 0.9 -1.3)
			(end 0.9 -0.4)
			(stroke
				(width 0.05)
				(type solid)
			)
			(layer "F.CrtYd")
		)
		(fp_line
			(start -0.9 -1.3)
			(end 0.9 -1.3)
			(stroke
				(width 0.05)
				(type solid)
			)
			(layer "F.CrtYd")
		)
		(fp_line
			(start -0.9 -1.3)
			(end -0.9 -1)
			(stroke
				(width 0.05)
				(type solid)
			)
			(layer "F.CrtYd")
		)
		(fp_line
			(start -0.9 -1)
			(end -1.4 -1)
			(stroke
				(width 0.05)
				(type solid)
			)
			(layer "F.CrtYd")
		)
		(fp_line
			(start 1.4 -0.4)
			(end 1.4 0.4)
			(stroke
				(width 0.05)
				(type solid)
			)
			(layer "F.CrtYd")
		)
		(fp_line
			(start 0.9 -0.4)
			(end 1.4 -0.4)
			(stroke
				(width 0.05)
				(type solid)
			)
			(layer "F.CrtYd")
		)
		(fp_line
			(start 1.4 0.4)
			(end 0.9 0.4)
			(stroke
				(width 0.05)
				(type solid)
			)
			(layer "F.CrtYd")
		)
		(fp_line
			(start 0.9 0.4)
			(end 0.9 1.3)
			(stroke
				(width 0.05)
				(type solid)
			)
			(layer "F.CrtYd")
		)
		(fp_line
			(start -0.9 1)
			(end -1.4 1)
			(stroke
				(width 0.05)
				(type solid)
			)
			(layer "F.CrtYd")
		)
		(fp_line
			(start -1.4 1)
			(end -1.4 -1)
			(stroke
				(width 0.05)
				(type solid)
			)
			(layer "F.CrtYd")
		)
		(fp_line
			(start 0.9 1.3)
			(end -0.9 1.3)
			(stroke
				(width 0.05)
				(type solid)
			)
			(layer "F.CrtYd")
		)
		(fp_line
			(start -0.9 1.3)
			(end -0.9 1)
			(stroke
				(width 0.05)
				(type solid)
			)
			(layer "F.CrtYd")
		)
		(fp_rect
			(start -0.623 -0.999)
			(end 0.627 1.001)
			(stroke
				(width 0.15)
				(type solid)
			)
			(fill no)
			(layer "F.Fab")
		)
		(pad "1" smd rect
			(at -0.95 -0.65 180)
			(size 0.6 0.8)
			(layers "F.Cu" "F.Mask" "F.Paste")
			(net 61 "USR_LED4")
			(pinfunction "G")
			(pintype "bidirectional")
		)
		(pad "2" smd rect
			(at -0.95 0.65 180)
			(size 0.6 0.8)
			(layers "F.Cu" "F.Mask" "F.Paste")
			(net 5 "GND")
			(pinfunction "S")
			(pintype "bidirectional")
		)
		(pad "3" smd rect
			(at 0.95 0 180)
			(size 0.6 0.8)
			(layers "F.Cu" "F.Mask" "F.Paste")
			(net 230 "Net-(Q4-D)")
			(pinfunction "D")
			(pintype "bidirectional")
		)
	)
	(footprint "antmicro-footprints:SC70-3"
		(layer "F.Cu")
		(at 206.736328 74.697157 90)
		(property "Reference" "Q5"
			(at -0.602843 -1.336328 90)
			(layer "F.SilkS")
			(effects
				(font
					(size 0.7 0.7)
					(thickness 0.15)
				)
				(justify left bottom)
			)
		)
		(property "Value" "BSS138PW"
			(at 0 2.3 90)
			(layer "F.Fab")
			(effects
				(font
					(size 0.7 0.7)
					(thickness 0.15)
				)
				(justify left bottom)
			)
		)
		(property "Description" "60 V, 320 mA N-channel enhancement mode Trench MOSFET, SC-70-3 aka SOT-323 package"
			(at 0 0 90)
			(layer "F.Fab")
			(hide yes)
			(effects
				(font
					(size 1.27 1.27)
					(thickness 0.15)
				)
			)
		)
		(property "Author" "Antmicro"
			(at 281.433485 -132.039171 0)
			(layer "F.Fab")
			(hide yes)
			(effects
				(font
					(size 1 1)
					(thickness 0.15)
				)
			)
		)
		(property "License" "Apache-2.0"
			(at 281.433485 -132.039171 0)
			(layer "F.Fab")
			(hide yes)
			(effects
				(font
					(size 1 1)
					(thickness 0.15)
				)
			)
		)
		(property "MPN" "BSS138PW"
			(at 281.433485 -132.039171 0)
			(layer "F.Fab")
			(hide yes)
			(effects
				(font
					(size 1 1)
					(thickness 0.15)
				)
			)
		)
		(property "Manufacturer" "Nexperia"
			(at 281.433485 -132.039171 0)
			(layer "F.Fab")
			(hide yes)
			(effects
				(font
					(size 1 1)
					(thickness 0.15)
				)
			)
		)
		(sheetname "Interfaces")
		(sheetfile "interfaces.kicad_sch")
		(attr smd)
		(fp_line
			(start -0.3 -1)
			(end 0.627 -0.999)
			(stroke
				(width 0.15)
				(type solid)
			)
			(layer "F.SilkS")
		)
		(fp_line
			(start 0.627 -0.6)
			(end 0.627 -0.999)
			(stroke
				(width 0.15)
				(type solid)
			)
			(layer "F.SilkS")
		)
		(fp_line
			(start 0.627 0.6)
			(end 0.627 1.001)
			(stroke
				(width 0.15)
				(type solid)
			)
			(layer "F.SilkS")
		)
		(fp_line
			(start -0.3 1)
			(end 0.627 1.001)
			(stroke
				(width 0.15)
				(type solid)
			)
			(layer "F.SilkS")
		)
		(fp_line
			(start 0.9 -1.3)
			(end 0.9 -0.4)
			(stroke
				(width 0.05)
				(type solid)
			)
			(layer "F.CrtYd")
		)
		(fp_line
			(start -0.9 -1.3)
			(end 0.9 -1.3)
			(stroke
				(width 0.05)
				(type solid)
			)
			(layer "F.CrtYd")
		)
		(fp_line
			(start -0.9 -1.3)
			(end -0.9 -1)
			(stroke
				(width 0.05)
				(type solid)
			)
			(layer "F.CrtYd")
		)
		(fp_line
			(start -0.9 -1)
			(end -1.4 -1)
			(stroke
				(width 0.05)
				(type solid)
			)
			(layer "F.CrtYd")
		)
		(fp_line
			(start 1.4 -0.4)
			(end 1.4 0.4)
			(stroke
				(width 0.05)
				(type solid)
			)
			(layer "F.CrtYd")
		)
		(fp_line
			(start 0.9 -0.4)
			(end 1.4 -0.4)
			(stroke
				(width 0.05)
				(type solid)
			)
			(layer "F.CrtYd")
		)
		(fp_line
			(start 1.4 0.4)
			(end 0.9 0.4)
			(stroke
				(width 0.05)
				(type solid)
			)
			(layer "F.CrtYd")
		)
		(fp_line
			(start 0.9 0.4)
			(end 0.9 1.3)
			(stroke
				(width 0.05)
				(type solid)
			)
			(layer "F.CrtYd")
		)
		(fp_line
			(start -0.9 1)
			(end -1.4 1)
			(stroke
				(width 0.05)
				(type solid)
			)
			(layer "F.CrtYd")
		)
		(fp_line
			(start -1.4 1)
			(end -1.4 -1)
			(stroke
				(width 0.05)
				(type solid)
			)
			(layer "F.CrtYd")
		)
		(fp_line
			(start 0.9 1.3)
			(end -0.9 1.3)
			(stroke
				(width 0.05)
				(type solid)
			)
			(layer "F.CrtYd")
		)
		(fp_line
			(start -0.9 1.3)
			(end -0.9 1)
			(stroke
				(width 0.05)
				(type solid)
			)
			(layer "F.CrtYd")
		)
		(fp_rect
			(start -0.623 -0.999)
			(end 0.627 1.001)
			(stroke
				(width 0.15)
				(type solid)
			)
			(fill no)
			(layer "F.Fab")
		)
		(pad "1" smd rect
			(at -0.95 -0.65 180)
			(size 0.6 0.8)
			(layers "F.Cu" "F.Mask" "F.Paste")
			(net 63 "USR_LED5")
			(pinfunction "G")
			(pintype "bidirectional")
		)
		(pad "2" smd rect
			(at -0.95 0.65 180)
			(size 0.6 0.8)
			(layers "F.Cu" "F.Mask" "F.Paste")
			(net 5 "GND")
			(pinfunction "S")
			(pintype "bidirectional")
		)
		(pad "3" smd rect
			(at 0.95 0 180)
			(size 0.6 0.8)
			(layers "F.Cu" "F.Mask" "F.Paste")
			(net 231 "Net-(Q5-D)")
			(pinfunction "D")
			(pintype "bidirectional")
		)
	)
	(footprint "antmicro-footprints:SW_B3U-1000P_SMD"
		(layer "F.Cu")
		(at 192.136328 67.947157 90)
		(property "Reference" "USR_BTN1"
			(at 0 -1.8 90)
			(layer "F.SilkS")
			(effects
				(font
					(size 0.7 0.7)
					(thickness 0.15)
				)
				(justify left bottom)
			)
		)
		(property "Value" "SW_B3U-1000P"
			(at 0 2.5 90)
			(layer "F.Fab")
			(effects
				(font
					(size 0.7 0.7)
					(thickness 0.15)
				)
				(justify left bottom)
			)
		)
		(property "Description" "Tactile Switch, B3U, Top Actuated, Surface Mount, Round Button, 153 gf, 50mA at 12VDC"
			(at 0 0 90)
			(layer "F.Fab")
			(hide yes)
			(effects
				(font
					(size 1.27 1.27)
					(thickness 0.15)
				)
			)
		)
		(property "Author" "Antmicro"
			(at 260.083485 -124.189171 0)
			(layer "F.Fab")
			(hide yes)
			(effects
				(font
					(size 1 1)
					(thickness 0.15)
				)
			)
		)
		(property "License" "Apache-2.0"
			(at 260.083485 -124.189171 0)
			(layer "F.Fab")
			(hide yes)
			(effects
				(font
					(size 1 1)
					(thickness 0.15)
				)
			)
		)
		(property "MPN" "B3U-1000P"
			(at 260.083485 -124.189171 0)
			(layer "F.Fab")
			(hide yes)
			(effects
				(font
					(size 1 1)
					(thickness 0.15)
				)
			)
		)
		(property "Manufacturer" "Omron"
			(at 260.083485 -124.189171 0)
			(layer "F.Fab")
			(hide yes)
			(effects
				(font
					(size 1 1)
					(thickness 0.15)
				)
			)
		)
		(sheetname "Interfaces")
		(sheetfile "interfaces.kicad_sch")
		(attr smd)
		(fp_line
			(start 1.6 -1.4)
			(end 1.1 -1.4)
			(stroke
				(width 0.15)
				(type solid)
			)
			(layer "F.SilkS")
		)
		(fp_line
			(start 1.6 -1.4)
			(end 1.6 -0.95)
			(stroke
				(width 0.15)
				(type solid)
			)
			(layer "F.SilkS")
		)
		(fp_line
			(start -1.6 -1.4)
			(end -1.1 -1.4)
			(stroke
				(width 0.15)
				(type solid)
			)
			(layer "F.SilkS")
		)
		(fp_line
			(start -1.6 -1.4)
			(end -1.601 -0.95)
			(stroke
				(width 0.15)
				(type solid)
			)
			(layer "F.SilkS")
		)
		(fp_line
			(start -1.601 -0.95)
			(end -2 -0.95)
			(stroke
				(width 0.15)
				(type solid)
			)
			(layer "F.SilkS")
		)
		(fp_line
			(start 1.6 1.4)
			(end 1.6 0.95)
			(stroke
				(width 0.15)
				(type solid)
			)
			(layer "F.SilkS")
		)
		(fp_line
			(start 1.6 1.4)
			(end 1.1 1.4)
			(stroke
				(width 0.15)
				(type solid)
			)
			(layer "F.SilkS")
		)
		(fp_line
			(start -1.6 1.4)
			(end -1.6 0.95)
			(stroke
				(width 0.15)
				(type solid)
			)
			(layer "F.SilkS")
		)
		(fp_line
			(start -1.6 1.4)
			(end -1.1 1.4)
			(stroke
				(width 0.15)
				(type solid)
			)
			(layer "F.SilkS")
		)
		(fp_rect
			(start -2.249 -1.55)
			(end 2.25 1.549)
			(stroke
				(width 0.05)
				(type solid)
			)
			(fill no)
			(layer "F.CrtYd")
		)
		(fp_rect
			(start -1.5 -1.29)
			(end 1.499 1.289)
			(stroke
				(width 0.15)
				(type solid)
			)
			(fill no)
			(layer "F.Fab")
		)
		(pad "1" smd rect
			(at -1.7 0 90)
			(size 0.8 1.7)
			(layers "F.Cu" "F.Mask" "F.Paste")
			(net 390 "USR_BTN1")
			(pinfunction "1")
			(pintype "passive")
		)
		(pad "2" smd rect
			(at 1.699 0 90)
			(size 0.8 1.7)
			(layers "F.Cu" "F.Mask" "F.Paste")
			(net 5 "GND")
			(pinfunction "2")
			(pintype "passive")
		)
	)
	(footprint "antmicro-footprints:SW_B3U-1000P_SMD"
		(layer "F.Cu")
		(at 196.536328 67.947157 90)
		(property "Reference" "USR_BTN2"
			(at 0 -1.8 90)
			(layer "F.SilkS")
			(effects
				(font
					(size 0.7 0.7)
					(thickness 0.15)
				)
				(justify left bottom)
			)
		)
		(property "Value" "SW_B3U-1000P"
			(at 0 2.5 90)
			(layer "F.Fab")
			(effects
				(font
					(size 0.7 0.7)
					(thickness 0.15)
				)
				(justify left bottom)
			)
		)
		(property "Description" "Tactile Switch, B3U, Top Actuated, Surface Mount, Round Button, 153 gf, 50mA at 12VDC"
			(at 0 0 90)
			(layer "F.Fab")
			(hide yes)
			(effects
				(font
					(size 1.27 1.27)
					(thickness 0.15)
				)
			)
		)
		(property "Author" "Antmicro"
			(at 264.483485 -128.589171 0)
			(layer "F.Fab")
			(hide yes)
			(effects
				(font
					(size 1 1)
					(thickness 0.15)
				)
			)
		)
		(property "License" "Apache-2.0"
			(at 264.483485 -128.589171 0)
			(layer "F.Fab")
			(hide yes)
			(effects
				(font
					(size 1 1)
					(thickness 0.15)
				)
			)
		)
		(property "MPN" "B3U-1000P"
			(at 264.483485 -128.589171 0)
			(layer "F.Fab")
			(hide yes)
			(effects
				(font
					(size 1 1)
					(thickness 0.15)
				)
			)
		)
		(property "Manufacturer" "Omron"
			(at 264.483485 -128.589171 0)
			(layer "F.Fab")
			(hide yes)
			(effects
				(font
					(size 1 1)
					(thickness 0.15)
				)
			)
		)
		(sheetname "Interfaces")
		(sheetfile "interfaces.kicad_sch")
		(attr smd)
		(fp_line
			(start 1.6 -1.4)
			(end 1.1 -1.4)
			(stroke
				(width 0.15)
				(type solid)
			)
			(layer "F.SilkS")
		)
		(fp_line
			(start 1.6 -1.4)
			(end 1.6 -0.95)
			(stroke
				(width 0.15)
				(type solid)
			)
			(layer "F.SilkS")
		)
		(fp_line
			(start -1.6 -1.4)
			(end -1.1 -1.4)
			(stroke
				(width 0.15)
				(type solid)
			)
			(layer "F.SilkS")
		)
		(fp_line
			(start -1.6 -1.4)
			(end -1.601 -0.95)
			(stroke
				(width 0.15)
				(type solid)
			)
			(layer "F.SilkS")
		)
		(fp_line
			(start -1.601 -0.95)
			(end -2 -0.95)
			(stroke
				(width 0.15)
				(type solid)
			)
			(layer "F.SilkS")
		)
		(fp_line
			(start 1.6 1.4)
			(end 1.6 0.95)
			(stroke
				(width 0.15)
				(type solid)
			)
			(layer "F.SilkS")
		)
		(fp_line
			(start 1.6 1.4)
			(end 1.1 1.4)
			(stroke
				(width 0.15)
				(type solid)
			)
			(layer "F.SilkS")
		)
		(fp_line
			(start -1.6 1.4)
			(end -1.6 0.95)
			(stroke
				(width 0.15)
				(type solid)
			)
			(layer "F.SilkS")
		)
		(fp_line
			(start -1.6 1.4)
			(end -1.1 1.4)
			(stroke
				(width 0.15)
				(type solid)
			)
			(layer "F.SilkS")
		)
		(fp_rect
			(start -2.249 -1.55)
			(end 2.25 1.549)
			(stroke
				(width 0.05)
				(type solid)
			)
			(fill no)
			(layer "F.CrtYd")
		)
		(fp_rect
			(start -1.5 -1.29)
			(end 1.499 1.289)
			(stroke
				(width 0.15)
				(type solid)
			)
			(fill no)
			(layer "F.Fab")
		)
		(pad "1" smd rect
			(at -1.7 0 90)
			(size 0.8 1.7)
			(layers "F.Cu" "F.Mask" "F.Paste")
			(net 391 "USR_BTN2")
			(pinfunction "1")
			(pintype "passive")
		)
		(pad "2" smd rect
			(at 1.699 0 90)
			(size 0.8 1.7)
			(layers "F.Cu" "F.Mask" "F.Paste")
			(net 5 "GND")
			(pinfunction "2")
			(pintype "passive")
		)
	)
)
